(kicad_pcb
	(version 20241229)
	(generator "pcbnew")
	(generator_version "9.0")
	(general
		(thickness 1.62)
		(legacy_teardrops no)
	)
	(paper "A4")
	(title_block
		(title "OCuLink to 10GbE adapter")
		(date "2026-02-23")
		(rev "1.1.0")
		(company "Antmicro Ltd")
		(comment 1 "www.antmicro.com")
		(comment 9 "footprints 199-202 of 510")
	)
	(layers
		(0 "F.Cu" signal)
		(4 "In1.Cu" signal)
		(6 "In2.Cu" signal)
		(8 "In3.Cu" signal)
		(10 "In4.Cu" signal)
		(12 "In5.Cu" signal)
		(14 "In6.Cu" signal)
		(2 "B.Cu" signal)
		(9 "F.Adhes" user "F.Adhesive")
		(11 "B.Adhes" user "B.Adhesive")
		(13 "F.Paste" user)
		(15 "B.Paste" user)
		(5 "F.SilkS" user "F.Silkscreen")
		(7 "B.SilkS" user "B.Silkscreen")
		(1 "F.Mask" user)
		(3 "B.Mask" user)
		(17 "Dwgs.User" user "User.Drawings")
		(19 "Cmts.User" user "User.Comments")
		(21 "Eco1.User" user "User.Eco1")
		(23 "Eco2.User" user "User.Eco2")
		(25 "Edge.Cuts" user)
		(27 "Margin" user)
		(31 "F.CrtYd" user "F.Courtyard")
		(29 "B.CrtYd" user "B.Courtyard")
		(35 "F.Fab" user)
		(33 "B.Fab" user)
	)
	(footprint "antmicro-footprints:C_0402_1005Metric"
		(layer "F.Cu")
		(at 70.499998 78.339995 180)
		(descr "Capacitor SMD 0402")
		(tags "capacitor SMD 0402")
		(property "Reference" "C5"
			(at -2.230002 0.309995 0)
			(layer "F.SilkS")
			(effects
				(font
					(size 0.7 0.7)
					(thickness 0.15)
				)
				(justify right top)
			)
		)
		(property "Value" "C_100n_0402"
			(at -1.022927 2.155213 0)
			(layer "F.Fab")
			(hide yes)
			(effects
				(font
					(size 0.7 0.7)
					(thickness 0.15)
				)
				(justify right top)
			)
		)
		(property "Datasheet" "https://www.murata.com/products/productdetail?partno=GRM155R61H104KE14%23"
			(at 0 0 0)
			(layer "F.Fab")
			(hide yes)
			(effects
				(font
					(size 1.27 1.27)
					(thickness 0.15)
				)
			)
		)
		(property "Description" "SMD Multilayer Ceramic Capacitor, 0.1 µF, 50 V, 0402 [1005 Metric], ± 10%, X5R, GRM Series"
			(at 0 0 0)
			(layer "F.Fab")
			(hide yes)
			(effects
				(font
					(size 1.27 1.27)
					(thickness 0.15)
				)
			)
		)
		(property "MPN" "GRM155R61H104KE14D"
			(at 0 0 180)
			(unlocked yes)
			(layer "F.Fab")
			(hide yes)
			(effects
				(font
					(size 1 1)
					(thickness 0.15)
				)
			)
		)
		(property "Manufacturer" "Murata"
			(at 0 0 180)
			(unlocked yes)
			(layer "F.Fab")
			(hide yes)
			(effects
				(font
					(size 1 1)
					(thickness 0.15)
				)
			)
		)
		(property "License" "Apache-2.0"
			(at 0 0 180)
			(unlocked yes)
			(layer "F.Fab")
			(hide yes)
			(effects
				(font
					(size 1 1)
					(thickness 0.15)
				)
			)
		)
		(property "Author" "Antmicro"
			(at 0 0 180)
			(unlocked yes)
			(layer "F.Fab")
			(hide yes)
			(effects
				(font
					(size 1 1)
					(thickness 0.15)
				)
			)
		)
		(property "Val" "100n"
			(at 0 0 180)
			(unlocked yes)
			(layer "F.Fab")
			(hide yes)
			(effects
				(font
					(size 1 1)
					(thickness 0.15)
				)
			)
		)
		(property "Voltage" "50V"
			(at 0 0 180)
			(unlocked yes)
			(layer "F.Fab")
			(hide yes)
			(effects
				(font
					(size 1 1)
					(thickness 0.15)
				)
			)
		)
		(property "Dielectric" "X5R"
			(at 0 0 180)
			(unlocked yes)
			(layer "F.Fab")
			(hide yes)
			(effects
				(font
					(size 1 1)
					(thickness 0.15)
				)
			)
		)
		(sheetname "/Power/")
		(sheetfile "power.kicad_sch")
		(attr smd)
		(fp_rect
			(start -0.925 -0.47)
			(end 0.925 0.47)
			(stroke
				(width 0.05)
				(type default)
			)
			(fill no)
			(layer "F.CrtYd")
		)
		(fp_line
			(start 0.504 0.248)
			(end -0.494 0.248)
			(stroke
				(width 0.15)
				(type solid)
			)
			(layer "F.Fab")
		)
		(fp_line
			(start 0.504 -0.25)
			(end 0.504 0.248)
			(stroke
				(width 0.15)
				(type solid)
			)
			(layer "F.Fab")
		)
		(fp_line
			(start -0.494 0.248)
			(end -0.494 -0.25)
			(stroke
				(width 0.15)
				(type solid)
			)
			(layer "F.Fab")
		)
		(fp_line
			(start -0.494 -0.25)
			(end 0.504 -0.25)
			(stroke
				(width 0.15)
				(type solid)
			)
			(layer "F.Fab")
		)
		(pad "1" smd roundrect
			(at -0.48 0 180)
			(size 0.59 0.64)
			(layers "F.Cu" "F.Mask" "F.Paste")
			(roundrect_rratio 0.25)
			(net 28 "GND")
			(pintype "passive")
		)
		(pad "2" smd roundrect
			(at 0.48 0 180)
			(size 0.59 0.64)
			(layers "F.Cu" "F.Mask" "F.Paste")
			(roundrect_rratio 0.25)
			(net 314 "VCC")
			(pintype "passive")
		)
	)
	(footprint "antmicro-footprints:C_0603_1608Metric_EIA"
		(layer "F.Cu")
		(at 66.7 84.900001 180)
		(descr "Capacitor SMD 0603, IPC-7351 Density Level A")
		(tags "Capacitor 0603")
		(property "Reference" "C122"
			(at -1.98 5.110001 0)
			(layer "F.SilkS")
			(effects
				(font
					(size 0.7 0.7)
					(thickness 0.15)
				)
				(justify right top)
			)
		)
		(property "Value" "C_22u_16V_0603"
			(at -1.42757 1.770288 0)
			(layer "F.Fab")
			(hide yes)
			(effects
				(font
					(size 0.7 0.7)
					(thickness 0.15)
				)
				(justify right top)
			)
		)
		(property "Datasheet" "https://product.samsungsem.com/mlcc/CL10A226MO7JZN.do"
			(at 0 0 0)
			(layer "F.Fab")
			(hide yes)
			(effects
				(font
					(size 1.27 1.27)
					(thickness 0.15)
				)
			)
		)
		(property "Description" "SMD Multilayer Ceramic Capacitor"
			(at 0 0 0)
			(layer "F.Fab")
			(hide yes)
			(effects
				(font
					(size 1.27 1.27)
					(thickness 0.15)
				)
			)
		)
		(property "MPN" "CL10A226MO7JZNC"
			(at 0 0 180)
			(unlocked yes)
			(layer "F.Fab")
			(hide yes)
			(effects
				(font
					(size 1 1)
					(thickness 0.15)
				)
			)
		)
		(property "Manufacturer" "Samsung Electro-Mechanics"
			(at 0 0 180)
			(unlocked yes)
			(layer "F.Fab")
			(hide yes)
			(effects
				(font
					(size 1 1)
					(thickness 0.15)
				)
			)
		)
		(property "License" "Apache-2.0"
			(at 0 0 180)
			(unlocked yes)
			(layer "F.Fab")
			(hide yes)
			(effects
				(font
					(size 1 1)
					(thickness 0.15)
				)
			)
		)
		(property "Author" "Antmicro"
			(at 0 0 180)
			(unlocked yes)
			(layer "F.Fab")
			(hide yes)
			(effects
				(font
					(size 1 1)
					(thickness 0.15)
				)
			)
		)
		(property "Val" "22u"
			(at 0 0 180)
			(unlocked yes)
			(layer "F.Fab")
			(hide yes)
			(effects
				(font
					(size 1 1)
					(thickness 0.15)
				)
			)
		)
		(property "Voltage" "16V"
			(at 0 0 180)
			(unlocked yes)
			(layer "F.Fab")
			(hide yes)
			(effects
				(font
					(size 1 1)
					(thickness 0.15)
				)
			)
		)
		(property "Dielectric" ""
			(at 0 0 180)
			(unlocked yes)
			(layer "F.Fab")
			(hide yes)
			(effects
				(font
					(size 1 1)
					(thickness 0.15)
				)
			)
		)
		(sheetname "/X710-AT2 power/")
		(sheetfile "x710-at2-power.kicad_sch")
		(attr smd)
		(fp_line
			(start -0.15 0.55)
			(end 0.15 0.55)
			(stroke
				(width 0.15)
				(type solid)
			)
			(layer "F.SilkS")
		)
		(fp_line
			(start -0.15 -0.55)
			(end 0.15 -0.55)
			(stroke
				(width 0.15)
				(type solid)
			)
			(layer "F.SilkS")
		)
		(fp_rect
			(start -1.25 -0.65)
			(end 1.25 0.65)
			(stroke
				(width 0.05)
				(type solid)
			)
			(fill no)
			(layer "F.CrtYd")
		)
		(fp_rect
			(start -0.8 -0.45)
			(end 0.8 0.45)
			(stroke
				(width 0.15)
				(type solid)
			)
			(fill no)
			(layer "F.Fab")
		)
		(pad "1" smd roundrect
			(at -0.7 0 180)
			(size 0.8 1.1)
			(layers "F.Cu" "F.Mask" "F.Paste")
			(roundrect_rratio 0.2)
			(net 28 "GND")
			(pintype "passive")
		)
		(pad "2" smd roundrect
			(at 0.7 0 180)
			(size 0.8 1.1)
			(layers "F.Cu" "F.Mask" "F.Paste")
			(roundrect_rratio 0.2)
			(net 9 "VCCD")
			(pintype "passive")
		)
	)
	(footprint "antmicro-footprints:Heatsink_ATS-61500R-C2-R0"
		(locked yes)
		(layer "F.Cu")
		(at 84.975 100 90)
		(property "Reference" "H1"
			(at -23.081282 26.535 90)
			(unlocked yes)
			(layer "F.SilkS")
			(effects
				(font
					(size 0.7 0.7)
					(thickness 0.15)
				)
				(justify left bottom)
			)
		)
		(property "Value" "Heatsink_ATS-61500R-C2-R0"
			(at -22.27 -17.825 90)
			(unlocked yes)
			(layer "F.Fab")
			(hide yes)
			(effects
				(font
					(size 0.7 0.7)
					(thickness 0.15)
				)
				(justify left bottom)
			)
		)
		(property "Datasheet" "https://www.qats.com/DataSheet/ATS-61500-Series-C2-R0"
			(at 0 0 90)
			(layer "F.Fab")
			(hide yes)
			(effects
				(font
					(size 1.27 1.27)
					(thickness 0.15)
				)
			)
		)
		(property "Description" "Heat Sinks fanSINK Assembly with Mounting Hardware"
			(at 0 0 90)
			(layer "F.Fab")
			(hide yes)
			(effects
				(font
					(size 1.27 1.27)
					(thickness 0.15)
				)
			)
		)
		(property "MPN" "ATS-61500R-C2-R0"
			(at 0 0 90)
			(unlocked yes)
			(layer "F.Fab")
			(hide yes)
			(effects
				(font
					(size 1 1)
					(thickness 0.15)
				)
			)
		)
		(property "Manufacturer" "Advanced Thermal Solutions"
			(at 0 0 90)
			(unlocked yes)
			(layer "F.Fab")
			(hide yes)
			(effects
				(font
					(size 1 1)
					(thickness 0.15)
				)
			)
		)
		(property "Author" "Antmicro"
			(at 0 0 90)
			(unlocked yes)
			(layer "F.Fab")
			(hide yes)
			(effects
				(font
					(size 1 1)
					(thickness 0.15)
				)
			)
		)
		(property "License" "Apache-2.0"
			(at 0 0 90)
			(unlocked yes)
			(layer "F.Fab")
			(hide yes)
			(effects
				(font
					(size 1 1)
					(thickness 0.15)
				)
			)
		)
		(property ki_fp_filters "Heatsink_*")
		(sheetname "/")
		(sheetfile "oculink-to-10gbe-adapter.kicad_sch")
		(attr exclude_from_pos_files exclude_from_bom dnp)
		(fp_circle
			(center 22 -22)
			(end 26.22 -22)
			(stroke
				(width 0.05)
				(type solid)
			)
			(fill no)
			(layer "F.CrtYd")
		)
		(fp_circle
			(center -22 -22)
			(end -17.78 -22)
			(stroke
				(width 0.05)
				(type solid)
			)
			(fill no)
			(layer "F.CrtYd")
		)
		(fp_circle
			(center 22 22)
			(end 26.22 22)
			(stroke
				(width 0.05)
				(type solid)
			)
			(fill no)
			(layer "F.CrtYd")
		)
		(fp_circle
			(center -22 22)
			(end -17.78 22)
			(stroke
				(width 0.05)
				(type solid)
			)
			(fill no)
			(layer "F.CrtYd")
		)
		(zone
			(net 0)
			(net_name "")
			(layers "F.Cu" "B.Cu" "In1.Cu" "In2.Cu" "In3.Cu" "In4.Cu" "In5.Cu" "In6.Cu")
			(hatch edge 0.5)
			(connect_pads
				(clearance 0)
			)
			(min_thickness 0.25)
			(filled_areas_thickness no)
			(keepout
				(tracks not_allowed)
				(vias not_allowed)
				(pads allowed)
				(copperpour not_allowed)
				(footprints allowed)
			)
			(placement
				(enabled no)
				(sheetname "")
			)
			(fill
				(thermal_gap 0.5)
				(thermal_bridge_width 0.5)
			)
			(polygon
				(pts
					(xy 62.95963 75.979643) (xy 62.675 76) (xy 62.396165 76.060657) (xy 62.1288 76.160379) (xy 61.878348 76.297136)
					(xy 61.649909 76.468144) (xy 61.448131 76.669922) (xy 61.277123 76.898361) (xy 61.140366 77.148813)
					(xy 61.040644 77.416178) (xy 60.979987 77.695013) (xy 60.95963 77.979643) (xy 60.979987 78.264273)
					(xy 61.040644 78.543108) (xy 61.140366 78.810473) (xy 61.277123 79.060925) (xy 61.448131 79.289364)
					(xy 61.649909 79.491142) (xy 61.878348 79.66215) (xy 62.1288 79.798907) (xy 62.396165 79.898629)
					(xy 62.675 79.959286) (xy 62.95963 79.979643) (xy 63.24426 79.959286) (xy 63.523095 79.898629)
					(xy 63.79046 79.798907) (xy 64.040912 79.66215) (xy 64.269351 79.491142) (xy 64.471129 79.289364)
					(xy 64.642137 79.060925) (xy 64.778894 78.810473) (xy 64.878616 78.543108) (xy 64.939273 78.264273)
					(xy 64.95963 77.979643) (xy 64.939273 77.695013) (xy 64.878616 77.416178) (xy 64.778894 77.148813)
					(xy 64.642137 76.898361) (xy 64.471129 76.669922) (xy 64.269351 76.468144) (xy 64.040912 76.297136)
					(xy 63.79046 76.160379) (xy 63.523095 76.060657) (xy 63.24426 76)
				)
			)
		)
		(zone
			(net 0)
			(net_name "")
			(layers "F.Cu" "B.Cu" "In1.Cu" "In2.Cu" "In3.Cu" "In4.Cu" "In5.Cu" "In6.Cu")
			(hatch edge 0.5)
			(connect_pads
				(clearance 0)
			)
			(min_thickness 0.25)
			(filled_areas_thickness no)
			(keepout
				(tracks not_allowed)
				(vias not_allowed)
				(pads allowed)
				(copperpour not_allowed)
				(footprints allowed)
			)
			(placement
				(enabled no)
				(sheetname "")
			)
			(fill
				(thermal_gap 0.5)
				(thermal_bridge_width 0.5)
			)
			(polygon
				(pts
					(xy 62.975 120) (xy 62.69037 120.020357) (xy 62.411535 120.081014) (xy 62.14417 120.180736) (xy 61.893718 120.317493)
					(xy 61.665279 120.488501) (xy 61.463501 120.690279) (xy 61.292493 120.918718) (xy 61.155736 121.16917)
					(xy 61.056014 121.436535) (xy 60.995357 121.71537) (xy 60.975 122) (xy 60.995357 122.28463) (xy 61.056014 122.563465)
					(xy 61.155736 122.83083) (xy 61.292493 123.081282) (xy 61.463501 123.309721) (xy 61.665279 123.511499)
					(xy 61.893718 123.682507) (xy 62.14417 123.819264) (xy 62.411535 123.918986) (xy 62.69037 123.979643)
					(xy 62.975 124) (xy 63.25963 123.979643) (xy 63.538465 123.918986) (xy 63.80583 123.819264) (xy 64.056282 123.682507)
					(xy 64.284721 123.511499) (xy 64.486499 123.309721) (xy 64.657507 123.081282) (xy 64.794264 122.83083)
					(xy 64.893986 122.563465) (xy 64.954643 122.28463) (xy 64.975 122) (xy 64.954643 121.71537) (xy 64.893986 121.436535)
					(xy 64.794264 121.16917) (xy 64.657507 120.918718) (xy 64.486499 120.690279) (xy 64.284721 120.488501)
					(xy 64.056282 120.317493) (xy 63.80583 120.180736) (xy 63.538465 120.081014) (xy 63.25963 120.020357)
				)
			)
		)
		(zone
			(net 0)
			(net_name "")
			(layers "F.Cu" "B.Cu" "In1.Cu" "In2.Cu" "In3.Cu" "In4.Cu" "In5.Cu" "In6.Cu")
			(hatch edge 0.5)
			(connect_pads
				(clearance 0)
			)
			(min_thickness 0.25)
			(filled_areas_thickness no)
			(keepout
				(tracks not_allowed)
				(vias not_allowed)
				(pads allowed)
				(copperpour not_allowed)
				(footprints allowed)
			)
			(placement
				(enabled no)
				(sheetname "")
			)
			(fill
				(thermal_gap 0.5)
				(thermal_bridge_width 0.5)
			)
			(polygon
				(pts
					(xy 106.956014 75.982507) (xy 106.671384 76.002864) (xy 106.392549 76.063521) (xy 106.125184 76.163243)
					(xy 105.874732 76.3) (xy 105.646293 76.471008) (xy 105.444515 76.672786) (xy 105.273507 76.901225)
					(xy 105.13675 77.151677) (xy 105.037028 77.419042) (xy 104.976371 77.697877) (xy 104.956014 77.982507)
					(xy 104.976371 78.267137) (xy 105.037028 78.545972) (xy 105.13675 78.813337) (xy 105.273507 79.063789)
					(xy 105.444515 79.292228) (xy 105.646293 79.494006) (xy 105.874732 79.665014) (xy 106.125184 79.801771)
					(xy 106.392549 79.901493) (xy 106.671384 79.96215) (xy 106.956014 79.982507) (xy 107.240644 79.96215)
					(xy 107.519479 79.901493) (xy 107.786844 79.801771) (xy 108.037296 79.665014) (xy 108.265735 79.494006)
					(xy 108.467513 79.292228) (xy 108.638521 79.063789) (xy 108.775278 78.813337) (xy 108.875 78.545972)
					(xy 108.935657 78.267137) (xy 108.956014 77.982507) (xy 108.935657 77.697877) (xy 108.875 77.419042)
					(xy 108.775278 77.151677) (xy 108.638521 76.901225) (xy 108.467513 76.672786) (xy 108.265735 76.471008)
					(xy 108.037296 76.3) (xy 107.786844 76.163243) (xy 107.519479 76.063521) (xy 107.240644 76.002864)
				)
			)
		)
		(zone
			(net 0)
			(net_name "")
			(layers "F.Cu" "B.Cu" "In1.Cu" "In2.Cu" "In3.Cu" "In4.Cu" "In5.Cu" "In6.Cu")
			(hatch edge 0.5)
			(connect_pads
				(clearance 0)
			)
			(min_thickness 0.25)
			(filled_areas_thickness no)
			(keepout
				(tracks not_allowed)
				(vias not_allowed)
				(pads allowed)
				(copperpour not_allowed)
				(footprints allowed)
			)
			(placement
				(enabled no)
				(sheetname "")
			)
			(fill
				(thermal_gap 0.5)
				(thermal_bridge_width 0.5)
			)
			(polygon
				(pts
					(xy 106.956014 120) (xy 106.671384 120.020357) (xy 106.392549 120.081014) (xy 106.125184 120.180736)
					(xy 105.874732 120.317493) (xy 105.646293 120.488501) (xy 105.444515 120.690279) (xy 105.273507 120.918718)
					(xy 105.13675 121.16917) (xy 105.037028 121.436535) (xy 104.976371 121.71537) (xy 104.956014 122)
					(xy 104.976371 122.28463) (xy 105.037028 122.563465) (xy 105.13675 122.83083) (xy 105.273507 123.081282)
					(xy 105.444515 123.309721) (xy 105.646293 123.511499) (xy 105.874732 123.682507) (xy 106.125184 123.819264)
					(xy 106.392549 123.918986) (xy 106.671384 123.979643) (xy 106.956014 124) (xy 107.240644 123.979643)
					(xy 107.519479 123.918986) (xy 107.786844 123.819264) (xy 108.037296 123.682507) (xy 108.265735 123.511499)
					(xy 108.467513 123.309721) (xy 108.638521 123.081282) (xy 108.775278 122.83083) (xy 108.875 122.563465)
					(xy 108.935657 122.28463) (xy 108.956014 122) (xy 108.935657 121.71537) (xy 108.875 121.436535)
					(xy 108.775278 121.16917) (xy 108.638521 120.918718) (xy 108.467513 120.690279) (xy 108.265735 120.488501)
					(xy 108.037296 120.317493) (xy 107.786844 120.180736) (xy 107.519479 120.081014) (xy 107.240644 120.020357)
				)
			)
		)
	)
	(footprint "antmicro-footprints:R_0402_1005Metric"
		(layer "F.Cu")
		(at 111.15 100.100001 -90)
		(descr "Resistor SMD 0402")
		(tags "resistor SMD 0402")
		(property "Reference" "R180"
			(at -0.800001 -1.45 90)
			(layer "F.SilkS")
			(effects
				(font
					(size 0.7 0.7)
					(thickness 0.15)
				)
				(justify left bottom)
			)
		)
		(property "Value" "R_10k_0402"
			(at -1.011843 1.772046 90)
			(layer "F.Fab")
			(hide yes)
			(effects
				(font
					(size 0.7 0.7)
					(thickness 0.15)
				)
				(justify right top)
			)
		)
		(property "Datasheet" "https://www.bourns.com/docs/product-datasheets/cr.pdf"
			(at 0 0 90)
			(layer "F.Fab")
			(hide yes)
			(effects
				(font
					(size 1.27 1.27)
					(thickness 0.15)
				)
			)
		)
		(property "Description" "SMD Chip Resistor, 10 kohm, ± 1%, 62.5 mW, 0402 [1005 Metric], Thick Film, General Purpose"
			(at 0 0 90)
			(layer "F.Fab")
			(hide yes)
			(effects
				(font
					(size 1.27 1.27)
					(thickness 0.15)
				)
			)
		)
		(property "MPN" "CR0402-FX-1002GLF"
			(at 0 0 270)
			(unlocked yes)
			(layer "F.Fab")
			(hide yes)
			(effects
				(font
					(size 1 1)
					(thickness 0.15)
				)
			)
		)
		(property "Manufacturer" "Bourns"
			(at 0 0 270)
			(unlocked yes)
			(layer "F.Fab")
			(hide yes)
			(effects
				(font
					(size 1 1)
					(thickness 0.15)
				)
			)
		)
		(property "License" "Apache-2.0"
			(at 0 0 270)
			(unlocked yes)
			(layer "F.Fab")
			(hide yes)
			(effects
				(font
					(size 1 1)
					(thickness 0.15)
				)
			)
		)
		(property "Author" "Antmicro"
			(at 0 0 270)
			(unlocked yes)
			(layer "F.Fab")
			(hide yes)
			(effects
				(font
					(size 1 1)
					(thickness 0.15)
				)
			)
		)
		(property "Val" "10k"
			(at 0 0 270)
			(unlocked yes)
			(layer "F.Fab")
			(hide yes)
			(effects
				(font
					(size 1 1)
					(thickness 0.15)
				)
			)
		)
		(property "Tolerance" "1%"
			(at 0 0 270)
			(unlocked yes)
			(layer "F.Fab")
			(hide yes)
			(effects
				(font
					(size 1 1)
					(thickness 0.15)
				)
			)
		)
		(sheetname "/Fan controller/")
		(sheetfile "fan-controller.kicad_sch")
		(attr smd exclude_from_pos_files exclude_from_bom dnp)
		(fp_rect
			(start -0.925 -0.47)
			(end 0.925 0.47)
			(stroke
				(width 0.05)
				(type default)
			)
			(fill no)
			(layer "F.CrtYd")
		)
		(fp_rect
			(start -0.5 -0.25)
			(end 0.5 0.25)
			(stroke
				(width 0.15)
				(type solid)
			)
			(fill no)
			(layer "F.Fab")
		)
		(pad "1" smd roundrect
			(at -0.48 0 270)
			(size 0.59 0.64)
			(layers "F.Cu" "F.Mask" "F.Paste")
			(roundrect_rratio 0.25)
			(net 28 "GND")
			(pintype "passive")
		)
		(pad "2" smd roundrect
			(at 0.48 0 270)
			(size 0.59 0.64)
			(layers "F.Cu" "F.Mask" "F.Paste")
			(roundrect_rratio 0.25)
			(net 400 "/Fan controller/SLOPE")
			(pintype "passive")
		)
	)
)
